# BASEBOARD_FAB2 (Tioga Pass) — schematic netlist excerpt (pin names and nets, part order shuffled) for the footprints in the layout excerpt that follows; sources: Cadence DE-HDL packaged netlist, KiCad conversion of Wiwynn_Tioga_Pass_MB.brd

C3D19  CAP_A  22.0UF 4V 20% X6S  pkg 0603V  page 76 : A = PVCCMCP_CPU1 ; B = GND
L4A1  INDUCTOR  0.47UH 1% IND  pkg SM  page 234 : INA = VR_PVPP_KLM_PHASE ; INB = PVPP_KLM

T1P1  TPAD-DIFF-4P-GP  pkg DISCRET-GB3  page 256
  \1\  = L1_85OHM_6INCH_DP
  \2\  = L1_85OHM_6INCH_DN
  GND1  = GND
  GND2  = GND

(kicad_pcb
	(version 20260206)
	(generator "pcbnew")
	(generator_version "10.0")
	(general
		(thickness 1.6)
		(legacy_teardrops no)
	)
	(paper "A4")
	(title_block
		(title "Wiwynn_Tioga_Pass_MB.brd")
		(comment 1 "Tioga Pass / footprints 1926-1928 of 4770")
	)
	(layers
		(0 "F.Cu" signal "TOP")
		(4 "In1.Cu" signal "L2GND")
		(6 "In2.Cu" signal "L3")
		(8 "In3.Cu" signal "L4GND")
		(10 "In4.Cu" signal "L5")
		(12 "In5.Cu" signal "L6GND")
		(14 "In6.Cu" signal "L7VCC")
		(16 "In7.Cu" signal "L8VCC")
		(18 "In8.Cu" signal "L9GND")
		(20 "In9.Cu" signal "L10")
		(22 "In10.Cu" signal "L11GND")
		(24 "In11.Cu" signal "L12")
		(26 "In12.Cu" signal "L13GND")
		(2 "B.Cu" signal "BOTTOM")
		(9 "F.Adhes" user "F.Adhesive")
		(11 "B.Adhes" user "B.Adhesive")
		(13 "F.Paste" user "Package Geometry/Pastemask Top")
		(15 "B.Paste" user "Package Geometry/Pastemask Bottom")
		(5 "F.SilkS" user "Ref Des/Silkscreen Top")
		(7 "B.SilkS" user "Ref Des/Silkscreen Bottom")
		(1 "F.Mask" user "Board Geometry/Soldermask Top")
		(3 "B.Mask" user "Board Geometry/Soldermask Bottom")
		(17 "Dwgs.User" user "User.Drawings")
		(19 "Cmts.User" user "User.Comments")
		(21 "Eco1.User" user "User.Eco1")
		(23 "Eco2.User" user "User.Eco2")
		(25 "Edge.Cuts" user "Board Geometry/Outline")
		(27 "Margin" user)
		(31 "F.CrtYd" user "Package Geometry/Place Bound Top")
		(29 "B.CrtYd" user "Package Geometry/Place Bound Bottom")
		(35 "F.Fab" user "Ref Des/Assembly Top")
		(33 "B.Fab" user "Ref Des/Assembly Bottom")
	)
	(footprint ""
		(layer "F.Cu")
		(at 110.70844 -73.318116)
		(property "Reference" "C3D19"
			(at 0 0 0)
			(layer "F.SilkS")
			(hide yes)
			(effects
				(font
					(size 1.27 1.27)
				)
			)
		)
		(property "Value" ""
			(at 0 0 0)
			(layer "F.Fab")
			(effects
				(font
					(size 1.27 1.27)
				)
			)
		)
		(duplicate_pad_numbers_are_jumpers no)
		(fp_poly
			(pts
				(xy -0.4953 -0.2032) (xy 0.4953 -0.2032) (xy 0.4953 1.6002) (xy -0.4953 1.6002)
			)
			(stroke
				(width 0)
				(type default)
			)
			(fill no)
			(layer "F.CrtYd")
		)
		(fp_line
			(start -0.4953 -0.2032)
			(end 0.4953 -0.2032)
			(stroke
				(width 0.1)
				(type default)
			)
			(layer "F.Fab")
		)
		(fp_line
			(start -0.4953 1.6002)
			(end -0.4953 -0.2032)
			(stroke
				(width 0.1)
				(type default)
			)
			(layer "F.Fab")
		)
		(fp_line
			(start 0.4953 -0.2032)
			(end 0.4953 1.6002)
			(stroke
				(width 0.1)
				(type default)
			)
			(layer "F.Fab")
		)
		(fp_line
			(start 0.4953 1.6002)
			(end -0.4953 1.6002)
			(stroke
				(width 0.1)
				(type default)
			)
			(layer "F.Fab")
		)
		(pad "1" smd rect
			(at 0 0)
			(size 0.762 0.889)
			(layers "F.Cu" "F.Mask" "F.Paste")
			(net "PVCCMCP_CPU1")
		)
		(pad "2" smd rect
			(at 0 1.397)
			(size 0.762 0.889)
			(layers "F.Cu" "F.Mask" "F.Paste")
			(net "GND")
		)
		(zone
			(layer "F.Cu")
			(hatch none 0.5)
			(connect_pads
				(clearance 0)
			)
			(min_thickness 0.25)
			(keepout
				(tracks not_allowed)
				(vias allowed)
				(pads allowed)
				(copperpour not_allowed)
				(footprints allowed)
			)
			(placement
				(enabled no)
				(sheetname "")
			)
			(fill
				(thermal_gap 0.5)
				(thermal_bridge_width 0.5)
				(island_removal_mode 0)
			)
			(polygon
				(pts
					(xy 110.32744 -72.873616) (xy 111.08944 -72.873616) (xy 111.08944 -72.365616) (xy 110.32744 -72.365616)
				)
			)
		)
	)
	(footprint ""
		(layer "F.Cu")
		(at 201.671936 11.952478 -90)
		(property "Reference" "T1P1"
			(at 0 0 270)
			(layer "F.SilkS")
			(hide yes)
			(effects
				(font
					(size 1.27 1.27)
				)
			)
		)
		(property "Value" "*"
			(at -3.302 1.12395 270)
			(unlocked yes)
			(layer "F.Fab")
			(hide yes)
			(effects
				(font
					(size 0.889 0.889)
					(thickness 0.1524)
				)
			)
		)
		(property "Device Type" "TPAD-DIFF-4P-GP_DISCRET-GB3-TPA"
			(at -3.302 -0.40005 270)
			(unlocked yes)
			(layer "F.Fab")
			(hide yes)
			(effects
				(font
					(size 0.889 0.889)
					(thickness 0.1524)
				)
			)
		)
		(duplicate_pad_numbers_are_jumpers no)
		(fp_line
			(start -2.286 2.286)
			(end 2.286 2.286)
			(stroke
				(width 0.1524)
				(type default)
			)
			(layer "F.SilkS")
		)
		(fp_line
			(start 2.286 2.286)
			(end 2.286 -2.286)
			(stroke
				(width 0.1524)
				(type default)
			)
			(layer "F.SilkS")
		)
		(fp_line
			(start -2.286 -2.286)
			(end -2.286 2.286)
			(stroke
				(width 0.1524)
				(type default)
			)
			(layer "F.SilkS")
		)
		(fp_line
			(start 2.286 -2.286)
			(end -2.286 -2.286)
			(stroke
				(width 0.1524)
				(type default)
			)
			(layer "F.SilkS")
		)
		(fp_line
			(start -2.413 -2.413)
			(end -2.413 -1.143)
			(stroke
				(width 0.4064)
				(type default)
			)
			(layer "F.SilkS")
		)
		(fp_line
			(start -1.143 -2.413)
			(end -2.413 -2.413)
			(stroke
				(width 0.4064)
				(type default)
			)
			(layer "F.SilkS")
		)
		(fp_rect
			(start -2.54 2.54)
			(end 2.54 -2.54)
			(stroke
				(width 0)
				(type default)
			)
			(fill no)
			(layer "F.CrtYd")
		)
		(fp_rect
			(start -2.54 2.54)
			(end 2.54 -2.54)
			(stroke
				(width 0)
				(type default)
			)
			(fill no)
			(layer "F.Fab")
		)
		(pad "1" thru_hole circle
			(at -1.27 -1.27 270)
			(size 1.524 1.524)
			(drill 0.9144)
			(layers "*.Cu" "*.Mask")
			(remove_unused_layers no)
			(net "L1_85OHM_6INCH_DP")
			(clearance -0.0508)
			(thermal_gap 0.127)
			(padstack
				(mode front_inner_back)
				(layer "Inner"
					(shape circle)
					(size 1.1684 1.1684)
					(clearance 0.127)
				)
				(layer "B.Cu"
					(shape circle)
					(size 1.524 1.524)
					(clearance -0.0508)
				)
			)
		)
		(pad "2" thru_hole circle
			(at 1.27 -1.27 270)
			(size 1.524 1.524)
			(drill 0.9144)
			(layers "*.Cu" "*.Mask")
			(remove_unused_layers no)
			(net "L1_85OHM_6INCH_DN")
			(clearance -0.0508)
			(thermal_gap 0.127)
			(padstack
				(mode front_inner_back)
				(layer "Inner"
					(shape circle)
					(size 1.1684 1.1684)
					(clearance 0.127)
				)
				(layer "B.Cu"
					(shape circle)
					(size 1.524 1.524)
					(clearance -0.0508)
				)
			)
		)
		(pad "GND1" thru_hole rect
			(at -1.27 1.27 270)
			(size 1.524 1.524)
			(drill 0.9144)
			(layers "*.Cu" "*.Mask")
			(remove_unused_layers no)
			(net "GND")
			(clearance -0.0508)
			(thermal_gap 0.127)
			(padstack
				(mode front_inner_back)
				(layer "Inner"
					(shape circle)
					(size 1.1684 1.1684)
					(clearance 0.127)
				)
				(layer "B.Cu"
					(shape rect)
					(size 1.524 1.524)
					(clearance -0.0508)
				)
			)
		)
		(pad "GND2" thru_hole rect
			(at 1.27 1.27 270)
			(size 1.524 1.524)
			(drill 0.9144)
			(layers "*.Cu" "*.Mask")
			(remove_unused_layers no)
			(net "GND")
			(clearance -0.0508)
			(thermal_gap 0.127)
			(padstack
				(mode front_inner_back)
				(layer "Inner"
					(shape circle)
					(size 1.1684 1.1684)
					(clearance 0.127)
				)
				(layer "B.Cu"
					(shape rect)
					(size 1.524 1.524)
					(clearance -0.0508)
				)
			)
		)
	)
	(footprint ""
		(layer "F.Cu")
		(at 171.9834 -138.1125 -90)
		(property "Reference" "L4A1"
			(at -4.43103 4.191 0)
			(unlocked yes)
			(layer "F.SilkS")
			(effects
				(font
					(size 0.7874 0.5842)
					(thickness 0.1524)
				)
				(justify left)
			)
		)
		(property "Value" ""
			(at 0 0 270)
			(layer "F.Fab")
			(effects
				(font
					(size 1.27 1.27)
				)
			)
		)
		(duplicate_pad_numbers_are_jumpers no)
		(fp_line
			(start -3.4036 6.1341)
			(end -3.4036 -0.6731)
			(stroke
				(width 0.1524)
				(type default)
			)
			(layer "F.SilkS")
		)
		(fp_line
			(start -2.5654 6.1341)
			(end -3.4036 6.1341)
			(stroke
				(width 0.1524)
				(type default)
			)
			(layer "F.SilkS")
		)
		(fp_line
			(start 3.4036 6.1341)
			(end 2.5654 6.1341)
			(stroke
				(width 0.1524)
				(type default)
			)
			(layer "F.SilkS")
		)
		(fp_line
			(start -3.4036 -0.6731)
			(end -2.5654 -0.6731)
			(stroke
				(width 0.1524)
				(type default)
			)
			(layer "F.SilkS")
		)
		(fp_line
			(start 2.5654 -0.6731)
			(end 3.4036 -0.6731)
			(stroke
				(width 0.1524)
				(type default)
			)
			(layer "F.SilkS")
		)
		(fp_line
			(start 3.4036 -0.6731)
			(end 3.4036 6.1341)
			(stroke
				(width 0.1524)
				(type default)
			)
			(layer "F.SilkS")
		)
		(fp_poly
			(pts
				(xy -3.4036 -0.6731) (xy -3.4036 6.1341) (xy 3.4036 6.1341) (xy 3.4036 -0.6731)
			)
			(stroke
				(width 0)
				(type default)
			)
			(fill no)
			(layer "F.CrtYd")
		)
		(fp_line
			(start -3.4036 6.1341)
			(end -3.4036 -0.6731)
			(stroke
				(width 0.1)
				(type default)
			)
			(layer "F.Fab")
		)
		(fp_line
			(start 3.4036 6.1341)
			(end -3.4036 6.1341)
			(stroke
				(width 0.1)
				(type default)
			)
			(layer "F.Fab")
		)
		(fp_line
			(start -3.4036 -0.6731)
			(end 3.4036 -0.6731)
			(stroke
				(width 0.1)
				(type default)
			)
			(layer "F.Fab")
		)
		(fp_line
			(start 3.4036 -0.6731)
			(end 3.4036 6.1341)
			(stroke
				(width 0.1)
				(type default)
			)
			(layer "F.Fab")
		)
		(pad "1" smd rect
			(at 0 0 270)
			(size 3.556 3.175)
			(layers "F.Cu" "F.Mask" "F.Paste")
			(net "VR_PVPP_KLM_PHASE")
		)
		(pad "2" smd rect
			(at 0 5.461 270)
			(size 3.556 3.175)
			(layers "F.Cu" "F.Mask" "F.Paste")
			(net "PVPP_KLM")
		)
	)
)
